# BASEBOARD_FAB2 (Tioga Pass) — schematic netlist excerpt (pin names and nets, part order shuffled) for the footprints in the layout excerpt that follows; sources: Cadence DE-HDL packaged netlist, KiCad conversion of Wiwynn_Tioga_Pass_MB.brd

C1M20  CAP_A  0.1UF 16V 10% X7R  pkg 0402V  page 186 : A = P3V3_STBY ; B = GND
R6W1  RES  4.75K 1% CHIP  pkg 0402  page 137 : A = P3V3_STBY ; B = PU_UV_HIGH_SET
C7T1  CAP  100UF 4V 20% X5R  pkg 0805  page 225 : A = PVDDQ_GHJ ; B = GND

(kicad_pcb
	(version 20260206)
	(generator "pcbnew")
	(generator_version "10.0")
	(general
		(thickness 1.6)
		(legacy_teardrops no)
	)
	(paper "A4")
	(title_block
		(title "Wiwynn_Tioga_Pass_MB.brd")
		(comment 1 "Tioga Pass / footprints 2984-2986 of 4770")
	)
	(layers
		(0 "F.Cu" signal "TOP")
		(4 "In1.Cu" signal "L2GND")
		(6 "In2.Cu" signal "L3")
		(8 "In3.Cu" signal "L4GND")
		(10 "In4.Cu" signal "L5")
		(12 "In5.Cu" signal "L6GND")
		(14 "In6.Cu" signal "L7VCC")
		(16 "In7.Cu" signal "L8VCC")
		(18 "In8.Cu" signal "L9GND")
		(20 "In9.Cu" signal "L10")
		(22 "In10.Cu" signal "L11GND")
		(24 "In11.Cu" signal "L12")
		(26 "In12.Cu" signal "L13GND")
		(2 "B.Cu" signal "BOTTOM")
		(9 "F.Adhes" user "F.Adhesive")
		(11 "B.Adhes" user "B.Adhesive")
		(13 "F.Paste" user "Package Geometry/Pastemask Top")
		(15 "B.Paste" user "Package Geometry/Pastemask Bottom")
		(5 "F.SilkS" user "Ref Des/Silkscreen Top")
		(7 "B.SilkS" user "Ref Des/Silkscreen Bottom")
		(1 "F.Mask" user "Board Geometry/Soldermask Top")
		(3 "B.Mask" user "Board Geometry/Soldermask Bottom")
		(17 "Dwgs.User" user "User.Drawings")
		(19 "Cmts.User" user "User.Comments")
		(21 "Eco1.User" user "User.Eco1")
		(23 "Eco2.User" user "User.Eco2")
		(25 "Edge.Cuts" user "Board Geometry/Outline")
		(27 "Margin" user)
		(31 "F.CrtYd" user "Package Geometry/Place Bound Top")
		(29 "B.CrtYd" user "Package Geometry/Place Bound Bottom")
		(35 "F.Fab" user "Ref Des/Assembly Top")
		(33 "B.Fab" user "Ref Des/Assembly Bottom")
	)
	(footprint ""
		(layer "B.Cu")
		(at 482.981 -114.554 90)
		(property "Reference" "C1M20"
			(at 0 0 90)
			(layer "B.SilkS")
			(hide yes)
			(effects
				(font
					(size 1.27 1.27)
				)
				(justify mirror)
			)
		)
		(property "Value" ""
			(at 0 0 90)
			(layer "B.Fab")
			(effects
				(font
					(size 1.27 1.27)
				)
				(justify mirror)
			)
		)
		(duplicate_pad_numbers_are_jumpers no)
		(fp_rect
			(start -0.3048 -0.1016)
			(end 0.3048 0.9906)
			(stroke
				(width 0)
				(type default)
			)
			(fill no)
			(layer "B.CrtYd")
		)
		(fp_line
			(start 0.3048 -0.1016)
			(end 0.3048 0.9906)
			(stroke
				(width 0.1)
				(type default)
			)
			(layer "B.Fab")
		)
		(fp_line
			(start -0.3048 -0.1016)
			(end 0.3048 -0.1016)
			(stroke
				(width 0.1)
				(type default)
			)
			(layer "B.Fab")
		)
		(fp_line
			(start 0.3048 0.9906)
			(end -0.3048 0.9906)
			(stroke
				(width 0.1)
				(type default)
			)
			(layer "B.Fab")
		)
		(fp_line
			(start -0.3048 0.9906)
			(end -0.3048 -0.1016)
			(stroke
				(width 0.1)
				(type default)
			)
			(layer "B.Fab")
		)
		(pad "1" smd rect
			(at 0 0 270)
			(size 0.508 0.508)
			(layers "B.Cu" "B.Mask" "B.Paste")
			(net "P3V3_STBY")
		)
		(pad "2" smd rect
			(at 0 0.889 270)
			(size 0.508 0.508)
			(layers "B.Cu" "B.Mask" "B.Paste")
			(net "GND")
		)
		(zone
			(layer "B.Cu")
			(hatch none 0.5)
			(connect_pads
				(clearance 0)
			)
			(min_thickness 0.25)
			(keepout
				(tracks allowed)
				(vias not_allowed)
				(pads allowed)
				(copperpour not_allowed)
				(footprints allowed)
			)
			(placement
				(enabled no)
				(sheetname "")
			)
			(fill
				(thermal_gap 0.5)
				(thermal_bridge_width 0.5)
				(island_removal_mode 0)
			)
			(polygon
				(pts
					(xy 483.235 -114.3) (xy 483.616 -114.3) (xy 483.616 -114.808) (xy 483.235 -114.808)
				)
			)
		)
		(zone
			(layer "B.Cu")
			(hatch none 0.5)
			(connect_pads
				(clearance 0)
			)
			(min_thickness 0.25)
			(keepout
				(tracks not_allowed)
				(vias allowed)
				(pads allowed)
				(copperpour not_allowed)
				(footprints allowed)
			)
			(placement
				(enabled no)
				(sheetname "")
			)
			(fill
				(thermal_gap 0.5)
				(thermal_bridge_width 0.5)
				(island_removal_mode 0)
			)
			(polygon
				(pts
					(xy 483.235 -114.3) (xy 483.616 -114.3) (xy 483.616 -114.808) (xy 483.235 -114.808)
				)
			)
		)
	)
	(footprint ""
		(layer "B.Cu")
		(at 111.605568 -27.305 90)
		(property "Reference" "C7T1"
			(at 0 0 90)
			(layer "B.SilkS")
			(hide yes)
			(effects
				(font
					(size 1.27 1.27)
				)
				(justify mirror)
			)
		)
		(property "Value" ""
			(at 0 0 90)
			(layer "B.Fab")
			(effects
				(font
					(size 1.27 1.27)
				)
				(justify mirror)
			)
		)
		(duplicate_pad_numbers_are_jumpers no)
		(fp_poly
			(pts
				(xy 0.7239 -0.2159) (xy -0.7239 -0.2159) (xy -0.7239 1.9939) (xy 0.7239 1.9939)
			)
			(stroke
				(width 0)
				(type default)
			)
			(fill no)
			(layer "B.CrtYd")
		)
		(fp_line
			(start 0.7239 -0.2159)
			(end 0.7239 1.9939)
			(stroke
				(width 0.1)
				(type default)
			)
			(layer "B.Fab")
		)
		(fp_line
			(start -0.7239 -0.2159)
			(end 0.7239 -0.2159)
			(stroke
				(width 0.1)
				(type default)
			)
			(layer "B.Fab")
		)
		(fp_line
			(start 0.7239 1.9939)
			(end -0.7239 1.9939)
			(stroke
				(width 0.1)
				(type default)
			)
			(layer "B.Fab")
		)
		(fp_line
			(start -0.7239 1.9939)
			(end -0.7239 -0.2159)
			(stroke
				(width 0.1)
				(type default)
			)
			(layer "B.Fab")
		)
		(pad "1" smd rect
			(at 0 0 270)
			(size 1.27 1.016)
			(layers "B.Cu" "B.Mask" "B.Paste")
			(net "PVDDQ_GHJ")
		)
		(pad "2" smd rect
			(at 0 1.778 270)
			(size 1.27 1.016)
			(layers "B.Cu" "B.Mask" "B.Paste")
			(net "GND")
		)
		(zone
			(layer "B.Cu")
			(hatch none 0.5)
			(connect_pads
				(clearance 0)
			)
			(min_thickness 0.25)
			(keepout
				(tracks not_allowed)
				(vias allowed)
				(pads allowed)
				(copperpour not_allowed)
				(footprints allowed)
			)
			(placement
				(enabled no)
				(sheetname "")
			)
			(fill
				(thermal_gap 0.5)
				(thermal_bridge_width 0.5)
				(island_removal_mode 0)
			)
			(polygon
				(pts
					(xy 112.113568 -27.94) (xy 112.113568 -26.67) (xy 112.875568 -26.67) (xy 112.875568 -27.94)
				)
			)
		)
	)
	(footprint ""
		(layer "B.Cu")
		(at 450.3674 -4.7498)
		(property "Reference" "R6W1"
			(at 0.8382 -0.67818 0)
			(unlocked yes)
			(layer "B.SilkS")
			(effects
				(font
					(size 0.4064 0.254)
					(thickness 0.1524)
				)
				(justify left mirror)
			)
		)
		(property "Value" ""
			(at 0 0 0)
			(layer "B.Fab")
			(effects
				(font
					(size 1.27 1.27)
				)
				(justify mirror)
			)
		)
		(duplicate_pad_numbers_are_jumpers no)
		(fp_poly
			(pts
				(xy 0.2794 -0.1016) (xy -0.2794 -0.1016) (xy -0.2794 0.9906) (xy 0.2794 0.9906)
			)
			(stroke
				(width 0)
				(type default)
			)
			(fill no)
			(layer "B.CrtYd")
		)
		(fp_line
			(start -0.2794 -0.1016)
			(end 0.2794 -0.1016)
			(stroke
				(width 0.1)
				(type default)
			)
			(layer "B.Fab")
		)
		(fp_line
			(start -0.2794 0.9906)
			(end -0.2794 -0.1016)
			(stroke
				(width 0.1)
				(type default)
			)
			(layer "B.Fab")
		)
		(fp_line
			(start 0.2794 -0.1016)
			(end 0.2794 0.9906)
			(stroke
				(width 0.1)
				(type default)
			)
			(layer "B.Fab")
		)
		(fp_line
			(start 0.2794 0.9906)
			(end -0.2794 0.9906)
			(stroke
				(width 0.1)
				(type default)
			)
			(layer "B.Fab")
		)
		(pad "1" smd rect
			(at 0 0 180)
			(size 0.508 0.508)
			(layers "B.Cu" "B.Mask" "B.Paste")
			(net "P3V3_STBY")
		)
		(pad "2" smd rect
			(at 0 0.889 180)
			(size 0.508 0.508)
			(layers "B.Cu" "B.Mask" "B.Paste")
			(net "PU_UV_HIGH_SET")
		)
		(zone
			(layer "B.Cu")
			(hatch none 0.5)
			(connect_pads
				(clearance 0)
			)
			(min_thickness 0.25)
			(keepout
				(tracks allowed)
				(vias not_allowed)
				(pads allowed)
				(copperpour not_allowed)
				(footprints allowed)
			)
			(placement
				(enabled no)
				(sheetname "")
			)
			(fill
				(thermal_gap 0.5)
				(thermal_bridge_width 0.5)
				(island_removal_mode 0)
			)
			(polygon
				(pts
					(xy 450.6214 -4.4958) (xy 450.1134 -4.4958) (xy 450.1134 -4.1148) (xy 450.6214 -4.1148)
				)
			)
		)
		(zone
			(layer "B.Cu")
			(hatch none 0.5)
			(connect_pads
				(clearance 0)
			)
			(min_thickness 0.25)
			(keepout
				(tracks not_allowed)
				(vias allowed)
				(pads allowed)
				(copperpour not_allowed)
				(footprints allowed)
			)
			(placement
				(enabled no)
				(sheetname "")
			)
			(fill
				(thermal_gap 0.5)
				(thermal_bridge_width 0.5)
				(island_removal_mode 0)
			)
			(polygon
				(pts
					(xy 450.6214 -4.1148) (xy 450.1134 -4.1148) (xy 450.1134 -4.4958) (xy 450.6214 -4.4958)
				)
			)
		)
	)
)
